FILE_TYPE = CONNECTIVITY;
{Allegro Design Entry HDL 17.2-2016 S081 (4005846) 1/11/2022}
"PAGE_NUMBER" = 323;
0"NC";
1"P12V_AUX\g";
2"P3V3_AUX\g";
3"P3V3_AUX\g";
4"P12V_AUX\g";
5"P12V_E1S_0\g";
6"P3V3_E1S_0_R\g";
7"P3V3_AUX\g";
8"GND\g";
9"GND\g";
10"GND\g";
11"GND\g";
12"GND\g";
13"GND\g";
14"GND\g";
15"GND\g";
16"GND\g";
17"GND\g";
18"GND\g";
19"GND\g";
20"GND\g";
21"GND\g";
22"GND\g";
23"GND\g";
24"P12V_E1S_IMON_0";
25"P12V_E1S_0_ISENSE_MPS_TIC";
26"P12V_E1S_0_ISENSE_MPS_MAM";
27"P12V_E1S_AVIN_PD_0";
28"P12V_E1S_OV_FB_0";
29"P12V_E1S_FLTB_0";
30"P12V_E1S_AVIN_PD_0";
31"HP_LVC3_E1S_0_HSC_PWRGD";
32"P12V_E1S_SS_0";
33"P12V_E1S_EN_0_R2";
34"P12V_E1S_ISET_0";
35"P12V_E1S_ISET_0_R";
36"E1S_0_EN";
37"P12V_E1S_TIMER_0";
38"P3V3_E1S_GATE_0_PU293";
39"P3V3_E1S_DVDT_0";
40"P3V3_E1S_MODE_0";
41"P3V3_E1S_EN_0_R2";
42"P3V3_E1S_ILIMIT_0";
43"E1S_0_EN";
%"UNIVERSAL_POWER"
"1","(-450,-725)","2","logical_power","I10";
;
HDL_POWER"P3V3_AUX"
CDS_LIB"logical_power";
"A"7;
%"UNIVERSAL_GND"
"1","(-1100,-2000)","0","logical_power","I2";
;
CDS_LIB"logical_power"
HDL_POWER"GND";
"A"18;
%"UNIVERSAL_GND"
"1","(1625,-2125)","0","logical_power","I28";
;
CDS_LIB"logical_power"
HDL_POWER"GND";
"A"21;
%"UNIVERSAL_GND"
"1","(125,-2000)","0","logical_power","I29";
;
CDS_LIB"logical_power"
HDL_POWER"GND";
"A"22;
%"Q_CAP"
"1","(-1100,-1625)","0","pure_quanta","I3";
;
PART_NUMBER"CH0396J0B04"
VOLTAGE"50V"
ROOM"E1S1_P3V3_BOM2"
MATERIAL"EMPTY"
VALUE"39PF"
PACK_TYPE"C0402"
LOCATION"PC2197"
TOLERANCE"5%"
CDS_LIB"pure_quanta"
$SEC"1"
CDS_SEC"1";
"B"
$PN"2"18;
"A"
$PN"1"40;
%"Q_CAP"
"1","(125,-1700)","0","pure_quanta","I30";
;
PART_NUMBER"CH3683K1B09"
VALUE"0.068UF"
VOLTAGE"16V"
MATERIAL"EMPTY"
PACK_TYPE"0402"
ROOM"E1S1_P3V3_BOM2"
LOCATION"PC2201"
TOLERANCE"10%"
CDS_LIB"pure_quanta"
$SEC"1"
CDS_SEC"1";
"B"
$PN"2"22;
"A"
$PN"1"39;
%"MP5016GQHLZ"
"1","(775,-1375)","0","pure_quanta","I31";
;
PART_NUMBER"AL005016007"
MATERIAL"EMPTY"
VALUE"MP5016GQH-L-Z"
PART_TYPE"SMLF"
ROOM"E1S1_P3V3_BOM2"
LOCATION"PU293"
NEEDS_NO_SIZE"TRUE"
CDS_LMAN_SYM_OUTLINE"-250,200,250,-200"
CDS_LIB"pure_quanta"
$SEC"1"
CDS_SEC"1";
"SOURCE"
$PN"6_7"6;
"GATE"
$PN"8"38;
"DV_DT"
$PN"10"39;
"VCC"
$PN"1_2"7;
"GND"
$PN"3"21;
"ILIMIT"
$PN"4"42;
"MODE"
$PN"5"40;
"EN"
$PN"9"41;
%"Q_CAP"
"1","(1625,-1775)","0","pure_quanta","I32";
;
PART_NUMBER"CH11006JB18"
TOLERANCE"5%"
VOLTAGE"50V"
MATERIAL"EMPTY"
PACK_TYPE"0402"
VALUE"100PF"
ROOM"E1S1_P3V3_BOM2"
LOCATION"PC2203"
CDS_LIB"pure_quanta"
$SEC"1"
CDS_SEC"1";
"B"
$PN"2"21;
"A"
$PN"1"38;
%"UNIVERSAL_GND"
"1","(2225,-1900)","0","logical_power","I33";
;
CDS_LIB"logical_power"
HDL_POWER"GND";
"A"23;
%"Q_CAP"
"1","(2225,-1550)","0","pure_quanta","I34";
;
PART_NUMBER"CH6103KEA01"
MATERIAL"EMPTY"
PACK_TYPE"C0805"
VOLTAGE"16V"
VALUE"10UF"
ROOM"E1S1_P3V3_BOM2"
LOCATION"PC2204"
CDS_LIB"pure_quanta"
TOLERANCE"10%"
$SEC"1"
CDS_SEC"1";
"B"
$PN"2"23;
"A"
$PN"1"6;
%"UNIVERSAL_POWER"
"1","(2225,-900)","2","logical_power","I35";
;
HDL_POWER"P3V3_E1S_0_R"
CDS_LIB"logical_power";
"A"6;
%"GND"
"1","(-2200,375)","0","logical_power","I36";
;
HDL_POWER"GND"
CDS_LIB"logical_power"
SIZE"1B";
"A<SIZE-1..0>\NAC"8;
%"Q_CAP"
"1","(-2200,725)","0","pure_quanta","I37";
;
PART_NUMBER"CH4223K1B00"
ROOM"E1S1_P12V_MPS_MAM_BOM3"
VALUE"0.22UF"
PACK_TYPE"0402"
MATERIAL"X7R"
VOLTAGE"16V"
LOCATION"PC2196"
TOLERANCE"10%"
CDS_LIB"pure_quanta"
ROOM1"E1S1_P12V_MPS_TIC_BOM4"
$SEC"1"
CDS_SEC"1";
"B"
$PN"2"8;
"A"
$PN"1"37;
%"GND"
"1","(-1775,300)","0","logical_power","I39";
;
HDL_POWER"GND"
CDS_LIB"logical_power"
SIZE"1B";
"A<SIZE-1..0>\NAC"9;
%"Q_RES"
"2","(-750,-1625)","0","pure_quanta","I4";
;
PART_NUMBER"CS37152FB05"
TOLERANCE"1%"
VALUE"71.5K"
MATERIAL"EMPTY"
PACK_TYPE"0402LF"
ROOM"E1S1_P3V3_BOM2"
LOCATION"PR3945"
CDS_LIB"pure_quanta"
WATTAGE"1/16W"
$SEC"1"
CDS_SEC"1";
"A"
$PN"1"40;
"B"
$PN"2"18;
%"Q_RES"
"2","(-1775,600)","0","pure_quanta","I40";
;
PART_NUMBER"CS34642FB02"
VALUE"46.4K"
PACK_TYPE"0402LF"
TOLERANCE"1%"
WATTAGE"1/16W"
MATERIAL"CHIP"
ROOM"E1S1_P12V_MPS_MAM_BOM3"
LOCATION"PR3944"
CDS_LIB"pure_quanta"
ROOM1"E1S1_P12V_MPS_TIC_BOM4"
$SEC"1"
CDS_SEC"1";
"A"
$PN"1"34;
"B"
$PN"2"9;
%"GND"
"1","(-1425,50)","0","logical_power","I41";
;
HDL_POWER"GND"
CDS_LIB"logical_power"
SIZE"1B";
"A<SIZE-1..0>\NAC"10;
%"Q_CAP"
"1","(-1425,275)","0","pure_quanta","I42";
;
PART_NUMBER"CH1566K1B09"
PACK_TYPE"C0402"
MATERIAL"X7R"
VOLTAGE"50V"
VALUE"560PF"
ROOM"E1S1_P12V_MPS_MAM_BOM3"
LOCATION"PC2341"
TOLERANCE"10%"
CDS_LIB"pure_quanta"
ROOM1"E1S1_P12V_MPS_TIC_BOM4"
$SEC"1"
CDS_SEC"1";
"B"
$PN"2"10;
"A"
$PN"1"35;
%"Q_RES"
"2","(-1425,600)","0","pure_quanta","I43";
;
PART_NUMBER"CS32002FB06"
WATTAGE"1/16W"
MATERIAL"CHIP"
TOLERANCE"1%"
VALUE"20K"
PACK_TYPE"0402LF"
ROOM"E1S1_P12V_MPS_MAM_BOM3"
LOCATION"PR4541"
CDS_LIB"pure_quanta"
ROOM1"E1S1_P12V_MPS_TIC_BOM4"
$SEC"1"
CDS_SEC"1";
"A"
$PN"1"34;
"B"
$PN"2"35;
%"GND"
"1","(-1300,925)","0","logical_power","I44";
;
HDL_POWER"GND"
SIZE"1B"
CDS_LIB"logical_power";
"A<SIZE-1..0>\NAC"11;
%"Q_RES"
"1","(-1425,1175)","0","pure_quanta","I45";
;
PART_NUMBER"CS00002JB13"
MATERIAL"CHIP"
WATTAGE"1/16W"
TOLERANCE"5%"
VALUE"0"
PACK_TYPE"0402LF"
ROOM"E1S1_P12V_MPS_MAM_BOM3"
$LOCATION"R3943"
CDS_LIB"pure_quanta"
ROOM1"E1S1_P12V_MPS_TIC_BOM4"
CDS_LOCATION"R3943"
$SEC"1"
CDS_SEC"1";
"B"
$PN"2"33;
"A"
$PN"1"36;
%"GND"
"1","(-900,275)","0","logical_power","I46";
;
HDL_POWER"GND"
SIZE"1B"
CDS_LIB"logical_power";
"A<SIZE-1..0>\NAC"12;
%"Q_CAP"
"1","(-900,500)","0","pure_quanta","I47";
;
PART_NUMBER"CH3474K1B04"
MATERIAL"X7R"
PACK_TYPE"C0402"
VOLTAGE"25V"
ROOM"E1S1_P12V_MPS_MAM_BOM3"
VALUE"0.047UF"
LOCATION"PC2281"
TOLERANCE"10%"
CDS_LIB"pure_quanta"
ROOM1"E1S1_P12V_MPS_TIC_BOM4"
$SEC"1"
CDS_SEC"1";
"B"
$PN"2"12;
"A"
$PN"1"32;
%"GND"
"1","(-559,441)","0","logical_power","I48";
;
HDL_POWER"GND"
SIZE"1B"
CDS_LIB"logical_power";
"A<SIZE-1..0>\NAC"13;
%"RS31312R"
"1","(-100,1050)","0","pure_quanta","I49";
;
PART_NUMBER"AL031312000"
ROOM"E1S1_P12V_MPS_MAM_BOM3"
VALUE"RS31312R"
MATERIAL"IC"
LOCATION"PU292"
PART_TYPE"SMLF"
CDS_LIB"pure_quanta"
NEEDS_NO_SIZE"TRUE"
CDS_LMAN_SYM_OUTLINE"-250,525,250,-525"
ROOM1"E1S1_P12V_MPS_TIC_BOM4"
$SEC"1"
CDS_SEC"1";
"GND"
$PN"7"13;
"SS"
$PN"6"32;
"ISET"
$PN"5"34;
"TIMER"
$PN"4"37;
"ENTM"
$PN"3"11;
"LOADEN"
$PN"2"11;
"EN"
$PN"1"33;
"VIN_26"
$PN"26"1;
"VIN_25"
$PN"25"1;
"VIN_24"
$PN"24"1;
"VIN_23"
$PN"23"1;
"IMON"
$PN"8"24;
"FLTB"
$PN"9"29;
"PG"
$PN"10"31;
"OV"
$PN"11"28;
"VOUT_13"
$PN"13"5;
"AVIN"
$PN"12"30;
"VOUT_14"
$PN"14"5;
"VOUT_15"
$PN"15"5;
"VOUT_16"
$PN"16"5;
"VOUT_17"
$PN"17"5;
"VOUT_18"
$PN"18"5;
"VOUT_19"
$PN"19"5;
"VIN_21_22"
$PN"21_22"1;
"VOUT_20"
$PN"20"5;
%"Q_RES"
"1","(-675,-1325)","0","pure_quanta","I5";
;
PART_NUMBER"CS00002JB13"
MATERIAL"EMPTY"
VALUE"0"
ROOM"E1S1_P3V3_BOM2"
WATTAGE"1/16W"
PACK_TYPE"0402LF"
TOLERANCE"5%"
$LOCATION"R3946"
CDS_LIB"pure_quanta"
CDS_LOCATION"R3946"
$SEC"1"
CDS_SEC"1";
"B"
$PN"2"41;
"A"
$PN"1"43;
%"GND"
"1","(-975,1350)","0","logical_power","I50";
;
HDL_POWER"GND"
CDS_LIB"logical_power"
SIZE"1B";
"A<SIZE-1..0>\NAC"14;
%"Q_CAP"
"1","(-975,1575)","0","pure_quanta","I51";
;
PART_NUMBER"CH5104KEB02"
ROOM"E1S1_P12V_MPS_MAM_BOM3"
VALUE"1UF"
MATERIAL"X6S"
PACK_TYPE"C0402"
VOLTAGE"25V"
LOCATION"PC2198"
TOLERANCE"10%"
CDS_LIB"pure_quanta"
ROOM1"E1S1_P12V_MPS_TIC_BOM4"
$SEC"1"
CDS_SEC"1";
"B"
$PN"2"14;
"A"
$PN"1"1;
%"UNIVERSAL_POWER"
"1","(-975,1925)","0","logical_power","I52";
;
HDL_POWER"P12V_AUX"
CDS_LIB"logical_power";
"A"1;
%"Q_RES"
"2","(525,300)","0","pure_quanta","I53";
;
PART_NUMBER"CS35602FB00"
PACK_TYPE"0402LF"
MATERIAL"CHIP"
WATTAGE"1/16W"
TOLERANCE"1%"
VALUE"56K"
ROOM"E1S1_P12V_MPS_MAM_BOM3"
LOCATION"PR3949"
CDS_LIB"pure_quanta"
ROOM1"E1S1_P12V_MPS_TIC_BOM4"
$SEC"1"
CDS_SEC"1";
"A"
$PN"1"24;
"B"
$PN"2"15;
%"Q_RES"
"1","(950,675)","0","pure_quanta","I54";
;
PART_NUMBER"CS31002FB08"
VALUE"10K"
TOLERANCE"1%"
WATTAGE"1/16W"
PACK_TYPE"0402LF"
ROOM"E1S1_P12V_MPS_MAM_BOM3"
MATERIAL"CHIP"
LOCATION"PR3951"
CDS_LIB"pure_quanta"
ROOM1"E1S1_P12V_MPS_TIC_BOM4"
$SEC"1"
CDS_SEC"1";
"B"
$PN"2"2;
"A"
$PN"1"29;
%"Q_RES"
"2","(900,1150)","0","pure_quanta","I55";
;
PART_NUMBER"CS11002FB07"
TOLERANCE"1%"
WATTAGE"1/16W"
VALUE"100"
MATERIAL"EMPTY"
PACK_TYPE"0402LF"
LOCATION"PR3950"
CDS_LIB"pure_quanta"
$SEC"1"
CDS_SEC"1";
"A"
$PN"1"5;
"B"
$PN"2"30;
%"Q_CAP"
"1","(975,300)","0","pure_quanta","I56";
;
PART_NUMBER"CH4106K1B01"
PACK_TYPE"C0402"
MATERIAL"X7R"
VALUE"100NF"
VOLTAGE"50V"
ROOM"E1S1_P12V_MPS_MAM_BOM3"
LOCATION"PC2202"
TOLERANCE"10%"
CDS_LIB"pure_quanta"
ROOM1"E1S1_P12V_MPS_TIC_BOM4"
$SEC"1"
CDS_SEC"1";
"B"
$PN"2"15;
"A"
$PN"1"24;
%"GND"
"1","(975,-100)","0","logical_power","I57";
;
HDL_POWER"GND"
SIZE"1B"
CDS_LIB"logical_power";
"A<SIZE-1..0>\NAC"15;
%"Q_RES"
"2","(1900,650)","0","pure_quanta","I58";
;
PART_NUMBER"CS31002FB08"
TOLERANCE"1%"
VALUE"10K"
ROOM"E1S1_P12V_MPS_MAM_BOM3"
PACK_TYPE"0402LF"
WATTAGE"1/16W"
MATERIAL"CHIP"
LOCATION"PR3954"
CDS_LIB"pure_quanta"
ROOM1"E1S1_P12V_MPS_TIC_BOM4"
$SEC"1"
CDS_SEC"1";
"A"
$PN"1"28;
"B"
$PN"2"16;
%"Q_RES"
"1","(-425,-1675)","1","pure_quanta","I6";
;
PART_NUMBER"CS22802FB04"
TOLERANCE"1%"
VALUE"2.8K"
PACK_TYPE"0402LF"
MATERIAL"EMPTY"
ROOM"E1S1_P3V3_BOM2"
LOCATION"PR3947"
CDS_LIB"pure_quanta"
WATTAGE"1/16W"
$SEC"1"
CDS_SEC"1";
"B"
$PN"2"42;
"A"
$PN"1"19;
%"VCCAUX15"
"1","(1525,725)","0","logical_power","I61";
;
HDL_POWER"P3V3_AUX"
CDS_LIB"logical_power";
"A"2;
%"Q_RES"
"2","(1500,1150)","0","pure_quanta","I62";
;
PART_NUMBER"CS37152FB05"
TOLERANCE"1%"
MATERIAL"EMPTY"
PACK_TYPE"0402LF"
VALUE"71.5K"
LOCATION"PR3952"
CDS_LIB"pure_quanta"
WATTAGE"1/16W"
$SEC"1"
CDS_SEC"1";
"A"
$PN"1"5;
"B"
$PN"2"28;
%"Q_RES"
"2","(1900,1075)","0","pure_quanta","I63";
;
PART_NUMBER"CS41202FB05"
TOLERANCE"1%"
PACK_TYPE"0402LF"
VALUE"120K"
WATTAGE"1/16W"
MATERIAL"CHIP"
ROOM"E1S1_P12V_MPS_MAM_BOM3"
LOCATION"PR3953"
CDS_LIB"pure_quanta"
ROOM1"E1S1_P12V_MPS_TIC_BOM4"
$SEC"1"
CDS_SEC"1";
"A"
$PN"1"4;
"B"
$PN"2"28;
%"Q_RES"
"2","(375,1750)","0","pure_quanta","I64";
;
PART_NUMBER"CS31002FB08"
PACK_TYPE"0402LF"
WATTAGE"1/16W"
ROOM"E1S1_P12V_MPS_MAM_BOM3"
TOLERANCE"1%"
MATERIAL"CHIP"
VALUE"10K"
LOCATION"R3948"
CDS_LIB"pure_quanta"
ROOM1"E1S1_P12V_MPS_TIC_BOM4"
$SEC"1"
CDS_SEC"1";
"A"
$PN"1"3;
"B"
$PN"2"31;
%"VCCAUX15"
"1","(375,1950)","0","logical_power","I65";
;
HDL_POWER"P3V3_AUX"
CDS_LIB"logical_power";
"A"3;
%"Q_RES"
"1","(2325,-25)","0","pure_quanta","I66";
;
PART_NUMBER"CS00002JB13"
VALUE"0"
ROOM1"E1S1_P12V_MPS_TIC_BOM4"
PACK_TYPE"0402LF"
WATTAGE"1/16W"
MATERIAL"CHIP"
TOLERANCE"5%"
$LOCATION"R3956"
CDS_LIB"pure_quanta"
CDS_LOCATION"R3956"
$SEC"1"
CDS_SEC"1";
"B"
$PN"2"25;
"A"
$PN"1"24;
%"Q_RES"
"1","(2325,150)","0","pure_quanta","I67";
;
PART_NUMBER"CS00002JB13"
ROOM"E1S1_P12V_MPS_MAM_BOM3"
VALUE"0"
TOLERANCE"5%"
WATTAGE"1/16W"
PACK_TYPE"0402LF"
MATERIAL"EMPTY"
$LOCATION"R3955"
CDS_LIB"pure_quanta"
CDS_LOCATION"R3955"
$SEC"1"
CDS_SEC"1";
"B"
$PN"2"26;
"A"
$PN"1"24;
%"GND"
"1","(2100,325)","0","logical_power","I68";
;
HDL_POWER"GND"
CDS_LIB"logical_power"
SIZE"1B";
"A<SIZE-1..0>\NAC"16;
%"Q_CAP"
"1","(2425,650)","0","pure_quanta","I69";
;
PART_NUMBER"CH5223M1900"
TOLERANCE"20%"
VALUE"2.2UF"
MATERIAL"X7R"
PACK_TYPE"C0603"
VOLTAGE"16V"
ROOM"E1S1_P12V_MPS_MAM_BOM3"
LOCATION"PC2205"
CDS_LIB"pure_quanta"
ROOM1"E1S1_P12V_MPS_TIC_BOM4"
$SEC"1"
CDS_SEC"1";
"B"
$PN"2"16;
"A"
$PN"1"27;
%"UNIVERSAL_GND"
"1","(-425,-2000)","0","logical_power","I7";
;
CDS_LIB"logical_power"
HDL_POWER"GND";
"A"19;
%"Q_RES"
"2","(2425,1075)","0","pure_quanta","I70";
;
PART_NUMBER"CS04993F909"
VALUE"49.9"
PACK_TYPE"0603LF"
MATERIAL"CHIP"
WATTAGE"1/10W"
TOLERANCE"1%"
ROOM"E1S1_P12V_MPS_MAM_BOM3"
LOCATION"PR3957"
CDS_LIB"pure_quanta"
ROOM1"E1S1_P12V_MPS_TIC_BOM4"
$SEC"1"
CDS_SEC"1";
"A"
$PN"1"4;
"B"
$PN"2"27;
%"UNIVERSAL_POWER"
"1","(2325,1375)","0","logical_power","I71";
;
HDL_POWER"P12V_AUX"
CDS_LIB"logical_power";
"A"4;
%"GND"
"1","(2775,1225)","0","logical_power","I72";
;
HDL_POWER"GND"
SIZE"1B"
CDS_LIB"logical_power";
"A<SIZE-1..0>\NAC"17;
%"Q_CAP"
"1","(2775,1500)","2","pure_quanta","I73";
;
PART_NUMBER"CH4104K1B00"
VOLTAGE"25V"
MATERIAL"X7R"
PACK_TYPE"0402"
TOLERANCE"10%"
VALUE"0.1UF"
ROOM"E1S1_P12V_MPS_MAM_BOM3"
LOCATION"PC2206"
CDS_LIB"pure_quanta"
ROOM1"E1S1_P12V_MPS_TIC_BOM4"
$SEC"1"
CDS_SEC"1";
"B"
$PN"2"17;
"A"
$PN"1"5;
%"UNIVERSAL_POWER"
"1","(2775,1775)","2","logical_power","I77";
;
HDL_POWER"P12V_E1S_0"
CDS_LIB"logical_power";
"A"5;
%"UNIVERSAL_GND"
"1","(-450,-1275)","0","logical_power","I8";
;
CDS_LIB"logical_power"
HDL_POWER"GND";
"A"20;
%"Q_CAP"
"1","(-450,-1050)","0","pure_quanta","I9";
;
PART_NUMBER"CH5104KEB02"
VOLTAGE"25V"
MATERIAL"EMPTY"
PACK_TYPE"C0402"
VALUE"1UF"
ROOM"E1S1_P3V3_BOM2"
LOCATION"PC2200"
TOLERANCE"10%"
CDS_LIB"pure_quanta"
$SEC"1"
CDS_SEC"1";
"B"
$PN"2"20;
"A"
$PN"1"7;
END.
